(kicad_pcb
	(version 20241229)
	(generator "pcbnew")
	(generator_version "9.0")
	(general
		(thickness 1.6296)
		(legacy_teardrops no)
	)
	(paper "A3")
	(title_block
		(title "Thunderbolt to 10GbE adapter")
		(date "2026-04-21")
		(rev "1.1.0")
		(company "Antmicro Ltd")
		(comment 1 "www.antmicro.com")
		(comment 9 "footprints 77-80 of 703")
	)
	(layers
		(0 "F.Cu" signal)
		(4 "In1.Cu" signal)
		(6 "In2.Cu" signal)
		(8 "In3.Cu" signal)
		(10 "In4.Cu" signal)
		(12 "In5.Cu" signal)
		(14 "In6.Cu" signal)
		(2 "B.Cu" signal)
		(9 "F.Adhes" user "F.Adhesive")
		(11 "B.Adhes" user "B.Adhesive")
		(13 "F.Paste" user)
		(15 "B.Paste" user)
		(5 "F.SilkS" user "F.Silkscreen")
		(7 "B.SilkS" user "B.Silkscreen")
		(1 "F.Mask" user)
		(3 "B.Mask" user)
		(17 "Dwgs.User" user "User.Drawings")
		(19 "Cmts.User" user "User.Comments")
		(21 "Eco1.User" user "User.Eco1")
		(23 "Eco2.User" user "User.Eco2")
		(25 "Edge.Cuts" user)
		(27 "Margin" user)
		(31 "F.CrtYd" user "F.Courtyard")
		(29 "B.CrtYd" user "B.Courtyard")
		(35 "F.Fab" user)
		(33 "B.Fab" user)
	)
	(footprint "antmicro-footprints:C_0402_1005Metric"
		(layer "F.Cu")
		(at 141.4 63.4 180)
		(descr "Capacitor SMD 0402")
		(tags "capacitor SMD 0402")
		(property "Reference" "C324"
			(at 1.4 -1.6 180)
			(layer "F.SilkS")
			(effects
				(font
					(size 0.7 0.7)
					(thickness 0.15)
				)
				(justify left bottom)
			)
		)
		(property "Value" "C_1u_25V_0402"
			(at -1.022927 2.155213 180)
			(layer "F.Fab")
			(effects
				(font
					(size 0.7 0.7)
					(thickness 0.15)
				)
				(justify left bottom)
			)
		)
		(property "Datasheet" "https://www.murata.com/products/productdetail?partno=GRM155R61E105KE11%23"
			(at 0 0 180)
			(layer "F.Fab")
			(hide yes)
			(effects
				(font
					(size 1.27 1.27)
					(thickness 0.15)
				)
			)
		)
		(property "Description" "SMD Multilayer Ceramic Capacitor, 1 µF, 25 V, 0402 [1005 Metric], ± 10%, X5R, GRM Series"
			(at 0 0 180)
			(layer "F.Fab")
			(hide yes)
			(effects
				(font
					(size 1.27 1.27)
					(thickness 0.15)
				)
			)
		)
		(property "MPN" "GRM155R61E105KE11J"
			(at 0 0 180)
			(unlocked yes)
			(layer "F.Fab")
			(hide yes)
			(effects
				(font
					(size 1 1)
					(thickness 0.15)
				)
			)
		)
		(property "Manufacturer" "Murata"
			(at 0 0 180)
			(unlocked yes)
			(layer "F.Fab")
			(hide yes)
			(effects
				(font
					(size 1 1)
					(thickness 0.15)
				)
			)
		)
		(property "License" "Apache-2.0"
			(at 0 0 180)
			(unlocked yes)
			(layer "F.Fab")
			(hide yes)
			(effects
				(font
					(size 1 1)
					(thickness 0.15)
				)
			)
		)
		(property "Author" "Antmicro"
			(at 0 0 180)
			(unlocked yes)
			(layer "F.Fab")
			(hide yes)
			(effects
				(font
					(size 1 1)
					(thickness 0.15)
				)
			)
		)
		(property "Val" "1u"
			(at 0 0 180)
			(unlocked yes)
			(layer "F.Fab")
			(hide yes)
			(effects
				(font
					(size 1 1)
					(thickness 0.15)
				)
			)
		)
		(property "Voltage" "25V"
			(at 0 0 180)
			(unlocked yes)
			(layer "F.Fab")
			(hide yes)
			(effects
				(font
					(size 1 1)
					(thickness 0.15)
				)
			)
		)
		(property "Dielectric" "X5R"
			(at 0 0 180)
			(unlocked yes)
			(layer "F.Fab")
			(hide yes)
			(effects
				(font
					(size 1 1)
					(thickness 0.15)
				)
			)
		)
		(sheetname "/Power input/")
		(sheetfile "power_input.kicad_sch")
		(attr smd)
		(fp_rect
			(start -0.925 -0.47)
			(end 0.925 0.47)
			(stroke
				(width 0.05)
				(type default)
			)
			(fill no)
			(layer "F.CrtYd")
		)
		(fp_line
			(start 0.504 0.248)
			(end -0.494 0.248)
			(stroke
				(width 0.15)
				(type solid)
			)
			(layer "F.Fab")
		)
		(fp_line
			(start 0.504 -0.25)
			(end 0.504 0.248)
			(stroke
				(width 0.15)
				(type solid)
			)
			(layer "F.Fab")
		)
		(fp_line
			(start -0.494 0.248)
			(end -0.494 -0.25)
			(stroke
				(width 0.15)
				(type solid)
			)
			(layer "F.Fab")
		)
		(fp_line
			(start -0.494 -0.25)
			(end 0.504 -0.25)
			(stroke
				(width 0.15)
				(type solid)
			)
			(layer "F.Fab")
		)
		(fp_text user "${REFERENCE}"
			(at -0.939 4.599 180)
			(layer "F.Fab")
			(effects
				(font
					(size 0.7 0.7)
					(thickness 0.15)
				)
				(justify left bottom)
			)
		)
		(fp_text user "Author: Antmicro"
			(at -0.939 3.399 180)
			(layer "F.Fab")
			(effects
				(font
					(size 0.7 0.7)
					(thickness 0.15)
				)
				(justify left bottom)
			)
		)
		(fp_text user "License: Apache-2.0"
			(at -0.939 5.799 180)
			(layer "F.Fab")
			(effects
				(font
					(size 0.7 0.7)
					(thickness 0.15)
				)
				(justify left bottom)
			)
		)
		(pad "1" smd roundrect
			(at -0.48 0 180)
			(size 0.59 0.64)
			(layers "F.Cu" "F.Mask" "F.Paste")
			(roundrect_rratio 0.25)
			(net 23 "GND")
			(pintype "passive")
		)
		(pad "2" smd roundrect
			(at 0.48 0 180)
			(size 0.59 0.64)
			(layers "F.Cu" "F.Mask" "F.Paste")
			(roundrect_rratio 0.25)
			(net 40 "+5V")
			(pintype "passive")
		)
	)
	(footprint "antmicro-footprints:FB_0603_1608Metric"
		(layer "F.Cu")
		(at 160.155 99.224999 90)
		(property "Reference" "FB6"
			(at 0 7.695 90)
			(layer "F.SilkS")
			(effects
				(font
					(size 0.7 0.7)
					(thickness 0.15)
				)
			)
		)
		(property "Value" "FB_33Z_3A_Murata-BLM18PG_0603"
			(at 0 1.5 90)
			(layer "F.Fab")
			(effects
				(font
					(size 0.7 0.7)
					(thickness 0.15)
				)
				(justify left bottom)
			)
		)
		(property "Datasheet" "https://www.murata.com/products/productdata/8796737273886/QNFA9101.pdf?1649080818000"
			(at 0 0 90)
			(layer "F.Fab")
			(hide yes)
			(effects
				(font
					(size 1.27 1.27)
					(thickness 0.15)
				)
			)
		)
		(property "Description" "Ferrite Bead, 0603 [1608 Metric], 33 ohm, 3 A, BLM18PG, 0.025 ohm, ± 25%, DC power line"
			(at 0 0 90)
			(layer "F.Fab")
			(hide yes)
			(effects
				(font
					(size 1.27 1.27)
					(thickness 0.15)
				)
			)
		)
		(property "Val" "33Z/3A"
			(at 0 0 90)
			(unlocked yes)
			(layer "F.Fab")
			(hide yes)
			(effects
				(font
					(size 1 1)
					(thickness 0.15)
				)
			)
		)
		(property "MPN" "BLM18PG330SH1D"
			(at 0 0 90)
			(unlocked yes)
			(layer "F.Fab")
			(hide yes)
			(effects
				(font
					(size 1 1)
					(thickness 0.15)
				)
			)
		)
		(property "Manufacturer" "Murata"
			(at 0 0 90)
			(unlocked yes)
			(layer "F.Fab")
			(hide yes)
			(effects
				(font
					(size 1 1)
					(thickness 0.15)
				)
			)
		)
		(property "Current" ""
			(at 0 0 90)
			(unlocked yes)
			(layer "F.Fab")
			(hide yes)
			(effects
				(font
					(size 1 1)
					(thickness 0.15)
				)
			)
		)
		(property "Author" "Antmicro"
			(at 0 0 90)
			(unlocked yes)
			(layer "F.Fab")
			(hide yes)
			(effects
				(font
					(size 1 1)
					(thickness 0.15)
				)
			)
		)
		(property "License" "Apache-2.0"
			(at 0 0 90)
			(unlocked yes)
			(layer "F.Fab")
			(hide yes)
			(effects
				(font
					(size 1 1)
					(thickness 0.15)
				)
			)
		)
		(sheetname "/X710-AT2 power/")
		(sheetfile "x710-at2-power.kicad_sch")
		(attr smd)
		(fp_line
			(start -0.15 -0.4)
			(end 0.15 -0.4)
			(stroke
				(width 0.15)
				(type solid)
			)
			(layer "F.SilkS")
		)
		(fp_line
			(start -0.15 0.4)
			(end 0.15 0.4)
			(stroke
				(width 0.15)
				(type solid)
			)
			(layer "F.SilkS")
		)
		(fp_rect
			(start -1.25 -0.65)
			(end 1.25 0.65)
			(stroke
				(width 0.05)
				(type solid)
			)
			(fill no)
			(layer "F.CrtYd")
		)
		(fp_line
			(start 0.8 -0.408)
			(end -0.803 -0.408)
			(stroke
				(width 0.15)
				(type solid)
			)
			(layer "F.Fab")
		)
		(fp_line
			(start 0.8 -0.408)
			(end 0.8 0.406)
			(stroke
				(width 0.15)
				(type solid)
			)
			(layer "F.Fab")
		)
		(fp_line
			(start 0.8 0.406)
			(end -0.803 0.406)
			(stroke
				(width 0.15)
				(type solid)
			)
			(layer "F.Fab")
		)
		(fp_line
			(start -0.803 0.406)
			(end -0.803 -0.408)
			(stroke
				(width 0.15)
				(type solid)
			)
			(layer "F.Fab")
		)
		(fp_text user "${REFERENCE}"
			(at -1.653 4.6 90)
			(layer "F.Fab")
			(effects
				(font
					(size 0.7 0.7)
					(thickness 0.15)
				)
				(justify left bottom)
			)
		)
		(fp_text user "Author: Antmicro"
			(at -1.653 3.162 90)
			(layer "F.Fab")
			(effects
				(font
					(size 0.7 0.7)
					(thickness 0.15)
				)
				(justify left bottom)
			)
		)
		(fp_text user "License: Apache-2.0"
			(at -1.653 5.9 90)
			(layer "F.Fab")
			(effects
				(font
					(size 0.7 0.7)
					(thickness 0.15)
				)
				(justify left bottom)
			)
		)
		(pad "1" smd roundrect
			(at -0.7 0 90)
			(size 0.8 1)
			(layers "F.Cu" "F.Mask" "F.Paste")
			(roundrect_rratio 0.2)
			(net 136 "+1V0")
			(pintype "passive")
		)
		(pad "2" smd roundrect
			(at 0.7 0 90)
			(size 0.8 1)
			(layers "F.Cu" "F.Mask" "F.Paste")
			(roundrect_rratio 0.2)
			(net 5 "P0_AVDDL")
			(pintype "passive")
		)
	)
	(footprint "antmicro-footprints:R_0402_1005Metric"
		(layer "F.Cu")
		(at 167.4 67.8 180)
		(descr "Resistor SMD 0402")
		(tags "resistor SMD 0402")
		(property "Reference" "R140"
			(at 0.2 -1.4 180)
			(layer "F.SilkS")
			(effects
				(font
					(size 0.7 0.7)
					(thickness 0.15)
				)
				(justify left bottom)
			)
		)
		(property "Value" "R_100R_0402"
			(at -1.011843 1.772047 180)
			(layer "F.Fab")
			(effects
				(font
					(size 0.7 0.7)
					(thickness 0.15)
				)
				(justify left bottom)
			)
		)
		(property "Datasheet" "https://www.bourns.com/docs/product-datasheets/cr.pdf"
			(at 0 0 180)
			(layer "F.Fab")
			(hide yes)
			(effects
				(font
					(size 1.27 1.27)
					(thickness 0.15)
				)
			)
		)
		(property "Description" "SMD Chip Resistor, 100 ohm, ± 1%, 62.5 mW, 0402 [1005 Metric], Thick Film, General Purpose"
			(at 0 0 180)
			(layer "F.Fab")
			(hide yes)
			(effects
				(font
					(size 1.27 1.27)
					(thickness 0.15)
				)
			)
		)
		(property "MPN" "CR0402-FX-1000GLF"
			(at 0 0 180)
			(unlocked yes)
			(layer "F.Fab")
			(hide yes)
			(effects
				(font
					(size 1 1)
					(thickness 0.15)
				)
			)
		)
		(property "Manufacturer" "Bourns"
			(at 0 0 180)
			(unlocked yes)
			(layer "F.Fab")
			(hide yes)
			(effects
				(font
					(size 1 1)
					(thickness 0.15)
				)
			)
		)
		(property "License" "Apache-2.0"
			(at 0 0 180)
			(unlocked yes)
			(layer "F.Fab")
			(hide yes)
			(effects
				(font
					(size 1 1)
					(thickness 0.15)
				)
			)
		)
		(property "Author" "Antmicro"
			(at 0 0 180)
			(unlocked yes)
			(layer "F.Fab")
			(hide yes)
			(effects
				(font
					(size 1 1)
					(thickness 0.15)
				)
			)
		)
		(property "Val" "100R"
			(at 0 0 180)
			(unlocked yes)
			(layer "F.Fab")
			(hide yes)
			(effects
				(font
					(size 1 1)
					(thickness 0.15)
				)
			)
		)
		(property "Tolerance" "1%"
			(at 0 0 180)
			(unlocked yes)
			(layer "F.Fab")
			(hide yes)
			(effects
				(font
					(size 1 1)
					(thickness 0.15)
				)
			)
		)
		(sheetname "/X710-AT2 Misc/")
		(sheetfile "x710-at2-mics.kicad_sch")
		(attr smd)
		(fp_rect
			(start -0.925 -0.47)
			(end 0.925 0.47)
			(stroke
				(width 0.05)
				(type default)
			)
			(fill no)
			(layer "F.CrtYd")
		)
		(fp_rect
			(start -0.5 -0.25)
			(end 0.5 0.25)
			(stroke
				(width 0.15)
				(type solid)
			)
			(fill no)
			(layer "F.Fab")
		)
		(fp_text user "Author: Antmicro"
			(at -0.95 4.169 180)
			(layer "F.Fab")
			(effects
				(font
					(size 0.7 0.7)
					(thickness 0.15)
				)
				(justify left bottom)
			)
		)
		(fp_text user "License: Apache-2.0"
			(at -0.95 5.169 180)
			(layer "F.Fab")
			(effects
				(font
					(size 0.7 0.7)
					(thickness 0.15)
				)
				(justify left bottom)
			)
		)
		(fp_text user "${REFERENCE}"
			(at -0.95 3.168 180)
			(layer "F.Fab")
			(effects
				(font
					(size 0.7 0.7)
					(thickness 0.15)
				)
				(justify left bottom)
			)
		)
		(pad "1" smd roundrect
			(at -0.48 0 180)
			(size 0.59 0.64)
			(layers "F.Cu" "F.Mask" "F.Paste")
			(roundrect_rratio 0.25)
			(net 23 "GND")
			(pintype "passive")
		)
		(pad "2" smd roundrect
			(at 0.48 0 180)
			(size 0.59 0.64)
			(layers "F.Cu" "F.Mask" "F.Paste")
			(roundrect_rratio 0.25)
			(net 438 "Net-(U17-B_{2})")
			(pintype "passive")
		)
	)
	(footprint "antmicro-footprints:Oscillator_SMD_Skyworks_SI511_5x3.2x1.17mm"
		(layer "F.Cu")
		(at 162 63 -90)
		(property "Reference" "Y4"
			(at -2.4 -2.4 90)
			(layer "F.SilkS")
			(effects
				(font
					(size 0.7 0.7)
					(thickness 0.15)
				)
				(justify left bottom)
			)
		)
		(property "Value" "Oscillator_25MHz_511ABA25M0000BAGR"
			(at -2.75 3.85 270)
			(layer "F.Fab")
			(effects
				(font
					(size 0.7 0.7)
					(thickness 0.15)
				)
				(justify left bottom)
			)
		)
		(property "Datasheet" "https://www.mouser.com/datasheet/2/472/si510_11-2507765.pdf"
			(at 0 0 270)
			(layer "F.Fab")
			(effects
				(font
					(size 0.7 0.7)
					(thickness 0.15)
				)
				(justify left bottom)
			)
		)
		(property "Description" "25 MHz XO (Standard) LVPECL Oscillator 3.3V Enable/Disable 6-SMD, No Lead"
			(at 0 0 270)
			(layer "F.Fab")
			(effects
				(font
					(size 0.7 0.7)
					(thickness 0.15)
				)
				(justify left bottom)
			)
		)
		(property "Manufacturer" "Skyworks Solutions"
			(at 0 0 270)
			(unlocked yes)
			(layer "F.Fab")
			(hide yes)
			(effects
				(font
					(size 1 1)
					(thickness 0.15)
				)
			)
		)
		(property "MPN" "511ABA25M0000BAGR"
			(at 0 0 270)
			(unlocked yes)
			(layer "F.Fab")
			(hide yes)
			(effects
				(font
					(size 1 1)
					(thickness 0.15)
				)
			)
		)
		(property "Val" "25 MHz"
			(at 0 0 270)
			(unlocked yes)
			(layer "F.Fab")
			(hide yes)
			(effects
				(font
					(size 1 1)
					(thickness 0.15)
				)
			)
		)
		(property "Author" "Antmicro"
			(at 0 0 270)
			(unlocked yes)
			(layer "F.Fab")
			(hide yes)
			(effects
				(font
					(size 1 1)
					(thickness 0.15)
				)
			)
		)
		(property "License" "Apache-2.0"
			(at 0 0 270)
			(unlocked yes)
			(layer "F.Fab")
			(hide yes)
			(effects
				(font
					(size 1 1)
					(thickness 0.15)
				)
			)
		)
		(sheetname "/X710-AT2 10GbE/")
		(sheetfile "x710-at2-10gbe.kicad_sch")
		(attr smd)
		(fp_line
			(start -1.6 2.5)
			(end 1.6 2.5)
			(stroke
				(width 0.15)
				(type solid)
			)
			(layer "F.SilkS")
		)
		(fp_line
			(start -1.6 2.5)
			(end -1.6 1.95)
			(stroke
				(width 0.15)
				(type solid)
			)
			(layer "F.SilkS")
		)
		(fp_line
			(start 1.6 2.5)
			(end 1.6 1.95)
			(stroke
				(width 0.15)
				(type solid)
			)
			(layer "F.SilkS")
		)
		(fp_line
			(start -1.6 -2.5)
			(end -1.6 -1.95)
			(stroke
				(width 0.15)
				(type solid)
			)
			(layer "F.SilkS")
		)
		(fp_line
			(start 1.6 -2.5)
			(end 1.6 -1.95)
			(stroke
				(width 0.15)
				(type solid)
			)
			(layer "F.SilkS")
		)
		(fp_line
			(start 1.6 -2.5)
			(end -1.6 -2.5)
			(stroke
				(width 0.15)
				(type solid)
			)
			(layer "F.SilkS")
		)
		(fp_circle
			(center -1.95 -1.875)
			(end -1.9 -1.875)
			(stroke
				(width 0.15)
				(type solid)
			)
			(fill yes)
			(layer "F.SilkS")
		)
		(fp_rect
			(start -2.25 -2.75)
			(end 2.25 2.75)
			(stroke
				(width 0.05)
				(type solid)
			)
			(fill no)
			(layer "F.CrtYd")
		)
		(fp_line
			(start -0.9 -2.5)
			(end -1.6 -1.8)
			(stroke
				(width 0.15)
				(type solid)
			)
			(layer "F.Fab")
		)
		(fp_rect
			(start -1.6 -2.5)
			(end 1.6 2.5)
			(stroke
				(width 0.15)
				(type solid)
			)
			(fill no)
			(layer "F.Fab")
		)
		(fp_text user "Author: Antmicro"
			(at -2.75 6.25 270)
			(layer "F.Fab")
			(effects
				(font
					(size 0.7 0.7)
					(thickness 0.15)
				)
				(justify left bottom)
			)
		)
		(fp_text user "${REFERENCE}"
			(at -2.75 7.45 270)
			(layer "F.Fab")
			(effects
				(font
					(size 0.7 0.7)
					(thickness 0.15)
				)
				(justify left bottom)
			)
		)
		(fp_text user "License: Apache-2.0"
			(at -2.75 5.05 270)
			(layer "F.Fab")
			(effects
				(font
					(size 0.7 0.7)
					(thickness 0.15)
				)
				(justify left bottom)
			)
		)
		(pad "1" smd rect
			(at -1.3 -1.27 270)
			(size 1.7 0.8)
			(layers "F.Cu" "F.Mask" "F.Paste")
			(net 113 "/X710-AT2 10GbE/EN_OSC")
			(pinfunction "EN")
			(pintype "input")
		)
		(pad "2" smd rect
			(at -1.3 0 270)
			(size 1.7 0.8)
			(layers "F.Cu" "F.Mask" "F.Paste")
			(net 594 "unconnected-(Y4-NC-Pad2)")
			(pinfunction "NC")
			(pintype "no_connect")
		)
		(pad "3" smd rect
			(at -1.3 1.27 270)
			(size 1.7 0.8)
			(layers "F.Cu" "F.Mask" "F.Paste")
			(net 23 "GND")
			(pinfunction "GND")
			(pintype "power_in")
		)
		(pad "4" smd rect
			(at 1.3 1.27 270)
			(size 1.7 0.8)
			(layers "F.Cu" "F.Mask" "F.Paste")
			(net 112 "/X710-AT2 10GbE/25MHZ_OSC_R.+")
			(pinfunction "OUT+")
			(pintype "output")
		)
		(pad "5" smd rect
			(at 1.3 0 270)
			(size 1.7 0.8)
			(layers "F.Cu" "F.Mask" "F.Paste")
			(net 114 "/X710-AT2 10GbE/25MHZ_OSC_R.-")
			(pinfunction "OUT-")
			(pintype "output")
		)
		(pad "6" smd rect
			(at 1.3 -1.27 270)
			(size 1.7 0.8)
			(layers "F.Cu" "F.Mask" "F.Paste")
			(net 56 "/X710-AT2 10GbE/3V3_OSC")
			(pinfunction "VCC")
			(pintype "power_in")
		)
	)
)
